# T6G (Grand Teton) — schematic netlist excerpt (pin names and nets, part order shuffled) for the footprints in the layout excerpt that follows; sources: Cadence DE-HDL packaged netlist, KiCad conversion of 04192023_DAF0TMB3IC0_F0TG_MB_C_brd_V02_OCP.brd

PC2227  Q_CAP  0.068UF 16V 10% X7R  pkg 0402  page 264 : A = HSC_SS ; B = AGND_HSC
R4081  Q_RES  10K 1% CHIP  pkg 0402LF  page 233 : A = P3V3_AUX ; B = CLK_GEN2_SMB_SADR

(kicad_pcb
	(version 20260206)
	(generator "pcbnew")
	(generator_version "10.0")
	(general
		(thickness 1.6)
		(legacy_teardrops no)
	)
	(paper "A4")
	(title_block
		(title "04192023_DAF0TMB3IC0_F0TG_MB_C_brd_V02_OCP.brd")
		(comment 1 "Grand Teton / footprints 472-473 of 8354")
	)
	(layers
		(0 "F.Cu" signal "TOP")
		(4 "In1.Cu" signal "GND")
		(6 "In2.Cu" signal "IN1")
		(8 "In3.Cu" signal "GND1")
		(10 "In4.Cu" signal "IN2")
		(12 "In5.Cu" signal "GND2")
		(14 "In6.Cu" signal "IN3")
		(16 "In7.Cu" signal "GND3")
		(18 "In8.Cu" signal "VCC")
		(20 "In9.Cu" signal "VCC1")
		(22 "In10.Cu" signal "GND4")
		(24 "In11.Cu" signal "IN4")
		(26 "In12.Cu" signal "GND5")
		(28 "In13.Cu" signal "IN5")
		(30 "In14.Cu" signal "GND6")
		(32 "In15.Cu" signal "IN6")
		(34 "In16.Cu" signal "GND7")
		(2 "B.Cu" signal "BOTTOM")
		(9 "F.Adhes" user "F.Adhesive")
		(11 "B.Adhes" user "B.Adhesive")
		(13 "F.Paste" user "Package Geometry/Pastemask Top")
		(15 "B.Paste" user "Package Geometry/Pastemask Bottom")
		(5 "F.SilkS" user "Ref Des/Silkscreen Top")
		(7 "B.SilkS" user "Ref Des/Silkscreen Bottom")
		(1 "F.Mask" user "Board Geometry/Soldermask Top")
		(3 "B.Mask" user "Board Geometry/Soldermask Bottom")
		(17 "Dwgs.User" user "User.Drawings")
		(19 "Cmts.User" user "User.Comments")
		(21 "Eco1.User" user "User.Eco1")
		(23 "Eco2.User" user "User.Eco2")
		(25 "Edge.Cuts" user "Board Geometry/Outline")
		(27 "Margin" user)
		(31 "F.CrtYd" user "Package Geometry/Place Bound Top")
		(29 "B.CrtYd" user "Package Geometry/Place Bound Bottom")
		(35 "F.Fab" user "Ref Des/Assembly Top")
		(33 "B.Fab" user "Ref Des/Assembly Bottom")
	)
	(footprint ""
		(layer "F.Cu")
		(at 8.334248 -131.32435)
		(property "Reference" "R4081"
			(at 0 0 0)
			(layer "F.SilkS")
			(hide yes)
			(effects
				(font
					(size 1.27 1.27)
				)
			)
		)
		(property "Value" ""
			(at 0 0 0)
			(layer "F.Fab")
			(effects
				(font
					(size 1.27 1.27)
				)
			)
		)
		(duplicate_pad_numbers_are_jumpers no)
		(fp_line
			(start -0.7874 -0.4064)
			(end 0.7874 -0.4064)
			(stroke
				(width 0.1524)
				(type default)
			)
			(layer "F.SilkS")
		)
		(fp_line
			(start -0.7874 0.4064)
			(end -0.7874 -0.4064)
			(stroke
				(width 0.1524)
				(type default)
			)
			(layer "F.SilkS")
		)
		(fp_line
			(start 0.7874 -0.4064)
			(end 0.7874 0.4064)
			(stroke
				(width 0.1524)
				(type default)
			)
			(layer "F.SilkS")
		)
		(fp_line
			(start 0.7874 0.4064)
			(end -0.7874 0.4064)
			(stroke
				(width 0.1524)
				(type default)
			)
			(layer "F.SilkS")
		)
		(fp_line
			(start -0.67945 -0.305054)
			(end -0.12065 -0.305054)
			(stroke
				(width 0.1)
				(type default)
			)
			(layer "F.Fab")
		)
		(fp_line
			(start -0.67945 0.3048)
			(end -0.67945 -0.305054)
			(stroke
				(width 0.1)
				(type default)
			)
			(layer "F.Fab")
		)
		(fp_line
			(start -0.12065 -0.305054)
			(end -0.12065 -0.2794)
			(stroke
				(width 0.1)
				(type default)
			)
			(layer "F.Fab")
		)
		(fp_line
			(start -0.12065 -0.2794)
			(end 0.12065 -0.2794)
			(stroke
				(width 0.1)
				(type default)
			)
			(layer "F.Fab")
		)
		(fp_line
			(start -0.12065 0.2794)
			(end -0.12065 0.3048)
			(stroke
				(width 0.1)
				(type default)
			)
			(layer "F.Fab")
		)
		(fp_line
			(start -0.12065 0.3048)
			(end -0.67945 0.3048)
			(stroke
				(width 0.1)
				(type default)
			)
			(layer "F.Fab")
		)
		(fp_line
			(start 0.120396 0.2794)
			(end -0.12065 0.2794)
			(stroke
				(width 0.1)
				(type default)
			)
			(layer "F.Fab")
		)
		(fp_line
			(start 0.120396 0.3048)
			(end 0.120396 0.2794)
			(stroke
				(width 0.1)
				(type default)
			)
			(layer "F.Fab")
		)
		(fp_line
			(start 0.12065 -0.3048)
			(end 0.67945 -0.3048)
			(stroke
				(width 0.1)
				(type default)
			)
			(layer "F.Fab")
		)
		(fp_line
			(start 0.12065 -0.2794)
			(end 0.12065 -0.3048)
			(stroke
				(width 0.1)
				(type default)
			)
			(layer "F.Fab")
		)
		(fp_line
			(start 0.67945 -0.3048)
			(end 0.67945 0.3048)
			(stroke
				(width 0.1)
				(type default)
			)
			(layer "F.Fab")
		)
		(fp_line
			(start 0.67945 0.3048)
			(end 0.120396 0.3048)
			(stroke
				(width 0.1)
				(type default)
			)
			(layer "F.Fab")
		)
		(pad "1" smd circle
			(at -0.40005 0)
			(size 0 0)
			(layers "F.Cu" "F.Mask" "F.Paste")
			(net "P3V3_AUX")
		)
		(pad "2" smd circle
			(at 0.40005 0)
			(size 0 0)
			(layers "F.Cu" "F.Mask" "F.Paste")
			(net "CLK_GEN2_SMB_SADR")
		)
	)
	(footprint ""
		(layer "F.Cu")
		(at 226.0981 -405.036782 180)
		(property "Reference" "PC2227"
			(at 0 0 180)
			(layer "F.SilkS")
			(hide yes)
			(effects
				(font
					(size 1.27 1.27)
				)
			)
		)
		(property "Value" ""
			(at 0 0 180)
			(layer "F.Fab")
			(effects
				(font
					(size 1.27 1.27)
				)
			)
		)
		(duplicate_pad_numbers_are_jumpers no)
		(fp_line
			(start 0.7874 0.4064)
			(end -0.7874 0.4064)
			(stroke
				(width 0.1524)
				(type default)
			)
			(layer "F.SilkS")
		)
		(fp_line
			(start 0.7874 -0.4064)
			(end 0.7874 0.4064)
			(stroke
				(width 0.1524)
				(type default)
			)
			(layer "F.SilkS")
		)
		(fp_line
			(start -0.7874 0.4064)
			(end -0.7874 -0.4064)
			(stroke
				(width 0.1524)
				(type default)
			)
			(layer "F.SilkS")
		)
		(fp_line
			(start -0.7874 -0.4064)
			(end 0.7874 -0.4064)
			(stroke
				(width 0.1524)
				(type default)
			)
			(layer "F.SilkS")
		)
		(fp_line
			(start 0.67945 0.3048)
			(end 0.120396 0.3048)
			(stroke
				(width 0.1)
				(type default)
			)
			(layer "F.Fab")
		)
		(fp_line
			(start 0.67945 -0.3048)
			(end 0.67945 0.3048)
			(stroke
				(width 0.1)
				(type default)
			)
			(layer "F.Fab")
		)
		(fp_line
			(start 0.12065 -0.2794)
			(end 0.12065 -0.3048)
			(stroke
				(width 0.1)
				(type default)
			)
			(layer "F.Fab")
		)
		(fp_line
			(start 0.12065 -0.3048)
			(end 0.67945 -0.3048)
			(stroke
				(width 0.1)
				(type default)
			)
			(layer "F.Fab")
		)
		(fp_line
			(start 0.120396 0.3048)
			(end 0.120396 0.2794)
			(stroke
				(width 0.1)
				(type default)
			)
			(layer "F.Fab")
		)
		(fp_line
			(start 0.120396 0.2794)
			(end -0.12065 0.2794)
			(stroke
				(width 0.1)
				(type default)
			)
			(layer "F.Fab")
		)
		(fp_line
			(start -0.12065 0.3048)
			(end -0.67945 0.3048)
			(stroke
				(width 0.1)
				(type default)
			)
			(layer "F.Fab")
		)
		(fp_line
			(start -0.12065 0.2794)
			(end -0.12065 0.3048)
			(stroke
				(width 0.1)
				(type default)
			)
			(layer "F.Fab")
		)
		(fp_line
			(start -0.12065 -0.2794)
			(end 0.12065 -0.2794)
			(stroke
				(width 0.1)
				(type default)
			)
			(layer "F.Fab")
		)
		(fp_line
			(start -0.12065 -0.305054)
			(end -0.12065 -0.2794)
			(stroke
				(width 0.1)
				(type default)
			)
			(layer "F.Fab")
		)
		(fp_line
			(start -0.67945 0.3048)
			(end -0.67945 -0.305054)
			(stroke
				(width 0.1)
				(type default)
			)
			(layer "F.Fab")
		)
		(fp_line
			(start -0.67945 -0.305054)
			(end -0.12065 -0.305054)
			(stroke
				(width 0.1)
				(type default)
			)
			(layer "F.Fab")
		)
		(pad "1" smd circle
			(at -0.40005 0 180)
			(size 0 0)
			(layers "F.Cu" "F.Mask" "F.Paste")
			(net "HSC_SS")
		)
		(pad "2" smd circle
			(at 0.40005 0 180)
			(size 0 0)
			(layers "F.Cu" "F.Mask" "F.Paste")
			(net "AGND_HSC")
		)
	)
)
